(kicad_pcb
	(version 20241229)
	(generator "pcbnew")
	(generator_version "9.0")
	(general
		(thickness 1.258)
		(legacy_teardrops no)
	)
	(paper "A4")
	(title_block
		(date "2024-05-27")
		(rev "1.1.2")
		(comment 9 "footprints 49-54 of 64")
	)
	(layers
		(0 "F.Cu" signal)
		(4 "In1.Cu" power)
		(6 "In2.Cu" power)
		(8 "In3.Cu" signal)
		(10 "In4.Cu" signal)
		(2 "B.Cu" signal)
		(9 "F.Adhes" user "F.Adhesive")
		(11 "B.Adhes" user "B.Adhesive")
		(13 "F.Paste" user)
		(15 "B.Paste" user)
		(5 "F.SilkS" user "F.Silkscreen")
		(7 "B.SilkS" user "B.Silkscreen")
		(1 "F.Mask" user)
		(3 "B.Mask" user)
		(17 "Dwgs.User" user "User.Drawings")
		(19 "Cmts.User" user "User.Comments")
		(21 "Eco1.User" user "User.Eco1")
		(23 "Eco2.User" user "User.Eco2")
		(25 "Edge.Cuts" user)
		(27 "Margin" user)
		(31 "F.CrtYd" user "F.Courtyard")
		(29 "B.CrtYd" user "B.Courtyard")
		(35 "F.Fab" user)
		(33 "B.Fab" user)
	)
	(footprint "antmicro-footprints:C_0201"
		(layer "B.Cu")
		(at 152.425 88.025 180)
		(descr "Capacitor SMD 0201")
		(tags "capacitor SMD 0201")
		(property "Reference" "C10"
			(at -1.175 -2.07 0)
			(layer "B.SilkS")
			(effects
				(font
					(size 0.7 0.7)
					(thickness 0.15)
				)
				(justify left bottom mirror)
			)
		)
		(property "Value" "C_100n_0201"
			(at 0 -1.4 0)
			(layer "B.Fab")
			(hide yes)
			(effects
				(font
					(size 0.7 0.7)
					(thickness 0.15)
				)
				(justify left bottom mirror)
			)
		)
		(property "Description" "SMD Multilayer Ceramic Capacitor, 0.1 µF, 6.3 V, 0201 [0603 Metric], ± 10%, X6S, CC Series"
			(at 0 0 180)
			(layer "F.Fab")
			(hide yes)
			(effects
				(font
					(size 1.27 1.27)
					(thickness 0.15)
				)
			)
		)
		(property "Author" "Antmicro"
			(at 304.85 176.05 0)
			(layer "B.Fab")
			(hide yes)
			(effects
				(font
					(size 1 1)
					(thickness 0.15)
				)
				(justify mirror)
			)
		)
		(property "Dielectric" ""
			(at 304.85 176.05 0)
			(layer "B.Fab")
			(hide yes)
			(effects
				(font
					(size 1 1)
					(thickness 0.15)
				)
				(justify mirror)
			)
		)
		(property "License" "Apache-2.0"
			(at 304.85 176.05 0)
			(layer "B.Fab")
			(hide yes)
			(effects
				(font
					(size 1 1)
					(thickness 0.15)
				)
				(justify mirror)
			)
		)
		(property "MPN" "CC0201KRX6S5BB104"
			(at 304.85 176.05 0)
			(layer "B.Fab")
			(hide yes)
			(effects
				(font
					(size 1 1)
					(thickness 0.15)
				)
				(justify mirror)
			)
		)
		(property "Manufacturer" "YAGEO"
			(at 304.85 176.05 0)
			(layer "B.Fab")
			(hide yes)
			(effects
				(font
					(size 1 1)
					(thickness 0.15)
				)
				(justify mirror)
			)
		)
		(property "Public" "False"
			(at 304.85 176.05 0)
			(layer "B.Fab")
			(hide yes)
			(effects
				(font
					(size 1 1)
					(thickness 0.15)
				)
				(justify mirror)
			)
		)
		(property "Val" "100n"
			(at 304.85 176.05 0)
			(layer "B.Fab")
			(hide yes)
			(effects
				(font
					(size 1 1)
					(thickness 0.15)
				)
				(justify mirror)
			)
		)
		(property "Voltage" ""
			(at 304.85 176.05 0)
			(layer "B.Fab")
			(hide yes)
			(effects
				(font
					(size 1 1)
					(thickness 0.15)
				)
				(justify mirror)
			)
		)
		(sheetname "DDR5")
		(sheetfile "ddr5.kicad_sch")
		(attr smd)
		(fp_rect
			(start -0.7 0.35)
			(end 0.7 -0.35)
			(stroke
				(width 0.05)
				(type default)
			)
			(fill no)
			(layer "B.CrtYd")
		)
		(fp_rect
			(start 0.3 -0.15)
			(end -0.301 0.149)
			(stroke
				(width 0.15)
				(type solid)
			)
			(fill no)
			(layer "B.Fab")
		)
		(pad "" smd roundrect
			(at -0.349 0.002 180)
			(size 0.318 0.36)
			(layers "B.Paste")
			(roundrect_rratio 0.25)
		)
		(pad "" smd roundrect
			(at 0.341 0.002 180)
			(size 0.318 0.36)
			(layers "B.Paste")
			(roundrect_rratio 0.25)
		)
		(pad "1" smd roundrect
			(at -0.321 0.002 180)
			(size 0.46 0.4)
			(layers "B.Cu" "B.Mask")
			(roundrect_rratio 0.25)
			(net 2 "VDDQ")
			(pintype "passive")
		)
		(pad "2" smd roundrect
			(at 0.32 0.002 180)
			(size 0.46 0.4)
			(layers "B.Cu" "B.Mask")
			(roundrect_rratio 0.25)
			(net 1 "GND")
			(pintype "passive")
		)
	)
	(footprint "antmicro-footprints:C_0201"
		(layer "B.Cu")
		(at 149.625 80.55 90)
		(descr "Capacitor SMD 0201")
		(tags "capacitor SMD 0201")
		(property "Reference" "C11"
			(at 2.95 0.445 270)
			(layer "B.SilkS")
			(effects
				(font
					(size 0.7 0.7)
					(thickness 0.15)
				)
				(justify left bottom mirror)
			)
		)
		(property "Value" "C_100n_0201"
			(at 0 -1.4 270)
			(layer "B.Fab")
			(hide yes)
			(effects
				(font
					(size 0.7 0.7)
					(thickness 0.15)
				)
				(justify left bottom mirror)
			)
		)
		(property "Description" "SMD Multilayer Ceramic Capacitor, 0.1 µF, 6.3 V, 0201 [0603 Metric], ± 10%, X6S, CC Series"
			(at 0 0 90)
			(layer "F.Fab")
			(hide yes)
			(effects
				(font
					(size 1.27 1.27)
					(thickness 0.15)
				)
			)
		)
		(property "Author" "Antmicro"
			(at 230.175 -69.075 0)
			(layer "B.Fab")
			(hide yes)
			(effects
				(font
					(size 1 1)
					(thickness 0.15)
				)
				(justify mirror)
			)
		)
		(property "Dielectric" ""
			(at 230.175 -69.075 0)
			(layer "B.Fab")
			(hide yes)
			(effects
				(font
					(size 1 1)
					(thickness 0.15)
				)
				(justify mirror)
			)
		)
		(property "License" "Apache-2.0"
			(at 230.175 -69.075 0)
			(layer "B.Fab")
			(hide yes)
			(effects
				(font
					(size 1 1)
					(thickness 0.15)
				)
				(justify mirror)
			)
		)
		(property "MPN" "CC0201KRX6S5BB104"
			(at 230.175 -69.075 0)
			(layer "B.Fab")
			(hide yes)
			(effects
				(font
					(size 1 1)
					(thickness 0.15)
				)
				(justify mirror)
			)
		)
		(property "Manufacturer" "YAGEO"
			(at 230.175 -69.075 0)
			(layer "B.Fab")
			(hide yes)
			(effects
				(font
					(size 1 1)
					(thickness 0.15)
				)
				(justify mirror)
			)
		)
		(property "Public" "False"
			(at 230.175 -69.075 0)
			(layer "B.Fab")
			(hide yes)
			(effects
				(font
					(size 1 1)
					(thickness 0.15)
				)
				(justify mirror)
			)
		)
		(property "Val" "100n"
			(at 230.175 -69.075 0)
			(layer "B.Fab")
			(hide yes)
			(effects
				(font
					(size 1 1)
					(thickness 0.15)
				)
				(justify mirror)
			)
		)
		(property "Voltage" ""
			(at 230.175 -69.075 0)
			(layer "B.Fab")
			(hide yes)
			(effects
				(font
					(size 1 1)
					(thickness 0.15)
				)
				(justify mirror)
			)
		)
		(sheetname "DDR5")
		(sheetfile "ddr5.kicad_sch")
		(attr smd)
		(fp_rect
			(start -0.7 0.35)
			(end 0.7 -0.35)
			(stroke
				(width 0.05)
				(type default)
			)
			(fill no)
			(layer "B.CrtYd")
		)
		(fp_rect
			(start 0.3 -0.15)
			(end -0.301 0.149)
			(stroke
				(width 0.15)
				(type solid)
			)
			(fill no)
			(layer "B.Fab")
		)
		(pad "" smd roundrect
			(at -0.349 0.002 90)
			(size 0.318 0.36)
			(layers "B.Paste")
			(roundrect_rratio 0.25)
		)
		(pad "" smd roundrect
			(at 0.341 0.002 90)
			(size 0.318 0.36)
			(layers "B.Paste")
			(roundrect_rratio 0.25)
		)
		(pad "1" smd roundrect
			(at -0.321 0.002 90)
			(size 0.46 0.4)
			(layers "B.Cu" "B.Mask")
			(roundrect_rratio 0.25)
			(net 2 "VDDQ")
			(pintype "passive")
		)
		(pad "2" smd roundrect
			(at 0.32 0.002 90)
			(size 0.46 0.4)
			(layers "B.Cu" "B.Mask")
			(roundrect_rratio 0.25)
			(net 1 "GND")
			(pintype "passive")
		)
	)
	(footprint "antmicro-footprints:C_0201"
		(layer "B.Cu")
		(at 151.625 83.675)
		(descr "Capacitor SMD 0201")
		(tags "capacitor SMD 0201")
		(property "Reference" "C28"
			(at 2.755 0.445 180)
			(layer "B.SilkS")
			(effects
				(font
					(size 0.7 0.7)
					(thickness 0.15)
				)
				(justify left bottom mirror)
			)
		)
		(property "Value" "C_100n_0201"
			(at 0 -1.4 180)
			(layer "B.Fab")
			(hide yes)
			(effects
				(font
					(size 0.7 0.7)
					(thickness 0.15)
				)
				(justify left bottom mirror)
			)
		)
		(property "Description" "SMD Multilayer Ceramic Capacitor, 0.1 µF, 6.3 V, 0201 [0603 Metric], ± 10%, X6S, CC Series"
			(at 0 0 0)
			(layer "F.Fab")
			(hide yes)
			(effects
				(font
					(size 1.27 1.27)
					(thickness 0.15)
				)
			)
		)
		(property "Author" "Antmicro"
			(at 0 0 0)
			(layer "B.Fab")
			(hide yes)
			(effects
				(font
					(size 1 1)
					(thickness 0.15)
				)
				(justify mirror)
			)
		)
		(property "Dielectric" ""
			(at 0 0 0)
			(layer "B.Fab")
			(hide yes)
			(effects
				(font
					(size 1 1)
					(thickness 0.15)
				)
				(justify mirror)
			)
		)
		(property "License" "Apache-2.0"
			(at 0 0 0)
			(layer "B.Fab")
			(hide yes)
			(effects
				(font
					(size 1 1)
					(thickness 0.15)
				)
				(justify mirror)
			)
		)
		(property "MPN" "CC0201KRX6S5BB104"
			(at 0 0 0)
			(layer "B.Fab")
			(hide yes)
			(effects
				(font
					(size 1 1)
					(thickness 0.15)
				)
				(justify mirror)
			)
		)
		(property "Manufacturer" "YAGEO"
			(at 0 0 0)
			(layer "B.Fab")
			(hide yes)
			(effects
				(font
					(size 1 1)
					(thickness 0.15)
				)
				(justify mirror)
			)
		)
		(property "Public" "False"
			(at 0 0 0)
			(layer "B.Fab")
			(hide yes)
			(effects
				(font
					(size 1 1)
					(thickness 0.15)
				)
				(justify mirror)
			)
		)
		(property "Val" "100n"
			(at 0 0 0)
			(layer "B.Fab")
			(hide yes)
			(effects
				(font
					(size 1 1)
					(thickness 0.15)
				)
				(justify mirror)
			)
		)
		(property "Voltage" ""
			(at 0 0 0)
			(layer "B.Fab")
			(hide yes)
			(effects
				(font
					(size 1 1)
					(thickness 0.15)
				)
				(justify mirror)
			)
		)
		(sheetname "DDR5")
		(sheetfile "ddr5.kicad_sch")
		(attr smd)
		(fp_rect
			(start -0.7 0.35)
			(end 0.7 -0.35)
			(stroke
				(width 0.05)
				(type default)
			)
			(fill no)
			(layer "B.CrtYd")
		)
		(fp_rect
			(start 0.3 -0.15)
			(end -0.301 0.149)
			(stroke
				(width 0.15)
				(type solid)
			)
			(fill no)
			(layer "B.Fab")
		)
		(pad "" smd roundrect
			(at -0.349 0.002)
			(size 0.318 0.36)
			(layers "B.Paste")
			(roundrect_rratio 0.25)
		)
		(pad "" smd roundrect
			(at 0.341 0.002)
			(size 0.318 0.36)
			(layers "B.Paste")
			(roundrect_rratio 0.25)
		)
		(pad "1" smd roundrect
			(at -0.321 0.002)
			(size 0.46 0.4)
			(layers "B.Cu" "B.Mask")
			(roundrect_rratio 0.25)
			(net 18 "VDD")
			(pintype "passive")
		)
		(pad "2" smd roundrect
			(at 0.32 0.002)
			(size 0.46 0.4)
			(layers "B.Cu" "B.Mask")
			(roundrect_rratio 0.25)
			(net 1 "GND")
			(pintype "passive")
		)
	)
	(footprint "antmicro-footprints:C_0201"
		(layer "B.Cu")
		(at 149.15 88.85 180)
		(descr "Capacitor SMD 0201")
		(tags "capacitor SMD 0201")
		(property "Reference" "C12"
			(at -0.86 -2.13 0)
			(layer "B.SilkS")
			(effects
				(font
					(size 0.7 0.7)
					(thickness 0.15)
				)
				(justify left bottom mirror)
			)
		)
		(property "Value" "C_100n_0201"
			(at 0 -1.4 0)
			(layer "B.Fab")
			(hide yes)
			(effects
				(font
					(size 0.7 0.7)
					(thickness 0.15)
				)
				(justify left bottom mirror)
			)
		)
		(property "Description" "SMD Multilayer Ceramic Capacitor, 0.1 µF, 6.3 V, 0201 [0603 Metric], ± 10%, X6S, CC Series"
			(at 0 0 180)
			(layer "F.Fab")
			(hide yes)
			(effects
				(font
					(size 1.27 1.27)
					(thickness 0.15)
				)
			)
		)
		(property "Author" "Antmicro"
			(at 298.3 177.7 0)
			(layer "B.Fab")
			(hide yes)
			(effects
				(font
					(size 1 1)
					(thickness 0.15)
				)
				(justify mirror)
			)
		)
		(property "Dielectric" ""
			(at 298.3 177.7 0)
			(layer "B.Fab")
			(hide yes)
			(effects
				(font
					(size 1 1)
					(thickness 0.15)
				)
				(justify mirror)
			)
		)
		(property "License" "Apache-2.0"
			(at 298.3 177.7 0)
			(layer "B.Fab")
			(hide yes)
			(effects
				(font
					(size 1 1)
					(thickness 0.15)
				)
				(justify mirror)
			)
		)
		(property "MPN" "CC0201KRX6S5BB104"
			(at 298.3 177.7 0)
			(layer "B.Fab")
			(hide yes)
			(effects
				(font
					(size 1 1)
					(thickness 0.15)
				)
				(justify mirror)
			)
		)
		(property "Manufacturer" "YAGEO"
			(at 298.3 177.7 0)
			(layer "B.Fab")
			(hide yes)
			(effects
				(font
					(size 1 1)
					(thickness 0.15)
				)
				(justify mirror)
			)
		)
		(property "Public" "False"
			(at 298.3 177.7 0)
			(layer "B.Fab")
			(hide yes)
			(effects
				(font
					(size 1 1)
					(thickness 0.15)
				)
				(justify mirror)
			)
		)
		(property "Val" "100n"
			(at 298.3 177.7 0)
			(layer "B.Fab")
			(hide yes)
			(effects
				(font
					(size 1 1)
					(thickness 0.15)
				)
				(justify mirror)
			)
		)
		(property "Voltage" ""
			(at 298.3 177.7 0)
			(layer "B.Fab")
			(hide yes)
			(effects
				(font
					(size 1 1)
					(thickness 0.15)
				)
				(justify mirror)
			)
		)
		(sheetname "DDR5")
		(sheetfile "ddr5.kicad_sch")
		(attr smd)
		(fp_rect
			(start -0.7 0.35)
			(end 0.7 -0.35)
			(stroke
				(width 0.05)
				(type default)
			)
			(fill no)
			(layer "B.CrtYd")
		)
		(fp_rect
			(start 0.3 -0.15)
			(end -0.301 0.149)
			(stroke
				(width 0.15)
				(type solid)
			)
			(fill no)
			(layer "B.Fab")
		)
		(pad "" smd roundrect
			(at -0.349 0.002 180)
			(size 0.318 0.36)
			(layers "B.Paste")
			(roundrect_rratio 0.25)
		)
		(pad "" smd roundrect
			(at 0.341 0.002 180)
			(size 0.318 0.36)
			(layers "B.Paste")
			(roundrect_rratio 0.25)
		)
		(pad "1" smd roundrect
			(at -0.321 0.002 180)
			(size 0.46 0.4)
			(layers "B.Cu" "B.Mask")
			(roundrect_rratio 0.25)
			(net 18 "VDD")
			(pintype "passive")
		)
		(pad "2" smd roundrect
			(at 0.32 0.002 180)
			(size 0.46 0.4)
			(layers "B.Cu" "B.Mask")
			(roundrect_rratio 0.25)
			(net 1 "GND")
			(pintype "passive")
		)
	)
	(footprint "antmicro-footprints:C_0201"
		(layer "B.Cu")
		(at 145.32 88.06 90)
		(descr "Capacitor SMD 0201")
		(tags "capacitor SMD 0201")
		(property "Reference" "C15"
			(at -0.65 0.37 270)
			(layer "B.SilkS")
			(effects
				(font
					(size 0.7 0.7)
					(thickness 0.15)
				)
				(justify left bottom mirror)
			)
		)
		(property "Value" "C_100n_0201"
			(at 0 -1.4 270)
			(layer "B.Fab")
			(hide yes)
			(effects
				(font
					(size 0.7 0.7)
					(thickness 0.15)
				)
				(justify left bottom mirror)
			)
		)
		(property "Description" "SMD Multilayer Ceramic Capacitor, 0.1 µF, 6.3 V, 0201 [0603 Metric], ± 10%, X6S, CC Series"
			(at 0 0 90)
			(layer "F.Fab")
			(hide yes)
			(effects
				(font
					(size 1.27 1.27)
					(thickness 0.15)
				)
			)
		)
		(property "Author" "Antmicro"
			(at 233.38 -57.26 0)
			(layer "B.Fab")
			(hide yes)
			(effects
				(font
					(size 1 1)
					(thickness 0.15)
				)
				(justify mirror)
			)
		)
		(property "Dielectric" ""
			(at 233.38 -57.26 0)
			(layer "B.Fab")
			(hide yes)
			(effects
				(font
					(size 1 1)
					(thickness 0.15)
				)
				(justify mirror)
			)
		)
		(property "License" "Apache-2.0"
			(at 233.38 -57.26 0)
			(layer "B.Fab")
			(hide yes)
			(effects
				(font
					(size 1 1)
					(thickness 0.15)
				)
				(justify mirror)
			)
		)
		(property "MPN" "CC0201KRX6S5BB104"
			(at 233.38 -57.26 0)
			(layer "B.Fab")
			(hide yes)
			(effects
				(font
					(size 1 1)
					(thickness 0.15)
				)
				(justify mirror)
			)
		)
		(property "Manufacturer" "YAGEO"
			(at 233.38 -57.26 0)
			(layer "B.Fab")
			(hide yes)
			(effects
				(font
					(size 1 1)
					(thickness 0.15)
				)
				(justify mirror)
			)
		)
		(property "Public" "False"
			(at 233.38 -57.26 0)
			(layer "B.Fab")
			(hide yes)
			(effects
				(font
					(size 1 1)
					(thickness 0.15)
				)
				(justify mirror)
			)
		)
		(property "Val" "100n"
			(at 233.38 -57.26 0)
			(layer "B.Fab")
			(hide yes)
			(effects
				(font
					(size 1 1)
					(thickness 0.15)
				)
				(justify mirror)
			)
		)
		(property "Voltage" ""
			(at 233.38 -57.26 0)
			(layer "B.Fab")
			(hide yes)
			(effects
				(font
					(size 1 1)
					(thickness 0.15)
				)
				(justify mirror)
			)
		)
		(sheetname "DDR5")
		(sheetfile "ddr5.kicad_sch")
		(attr smd)
		(fp_rect
			(start -0.7 0.35)
			(end 0.7 -0.35)
			(stroke
				(width 0.05)
				(type default)
			)
			(fill no)
			(layer "B.CrtYd")
		)
		(fp_rect
			(start 0.3 -0.15)
			(end -0.301 0.149)
			(stroke
				(width 0.15)
				(type solid)
			)
			(fill no)
			(layer "B.Fab")
		)
		(pad "" smd roundrect
			(at -0.349 0.002 90)
			(size 0.318 0.36)
			(layers "B.Paste")
			(roundrect_rratio 0.25)
		)
		(pad "" smd roundrect
			(at 0.341 0.002 90)
			(size 0.318 0.36)
			(layers "B.Paste")
			(roundrect_rratio 0.25)
		)
		(pad "1" smd roundrect
			(at -0.321 0.002 90)
			(size 0.46 0.4)
			(layers "B.Cu" "B.Mask")
			(roundrect_rratio 0.25)
			(net 18 "VDD")
			(pintype "passive")
		)
		(pad "2" smd roundrect
			(at 0.32 0.002 90)
			(size 0.46 0.4)
			(layers "B.Cu" "B.Mask")
			(roundrect_rratio 0.25)
			(net 1 "GND")
			(pintype "passive")
		)
	)
	(footprint "antmicro-footprints:C_0201"
		(layer "B.Cu")
		(at 146.75 88.05 180)
		(descr "Capacitor SMD 0201")
		(tags "capacitor SMD 0201")
		(property "Reference" "C1"
			(at -0.78 0.56 0)
			(layer "B.SilkS")
			(effects
				(font
					(size 0.7 0.7)
					(thickness 0.15)
				)
				(justify left bottom mirror)
			)
		)
		(property "Value" "C_100n_0201"
			(at 0 -1.4 0)
			(layer "B.Fab")
			(hide yes)
			(effects
				(font
					(size 0.7 0.7)
					(thickness 0.15)
				)
				(justify left bottom mirror)
			)
		)
		(property "Description" "SMD Multilayer Ceramic Capacitor, 0.1 µF, 6.3 V, 0201 [0603 Metric], ± 10%, X6S, CC Series"
			(at 0 0 180)
			(layer "F.Fab")
			(hide yes)
			(effects
				(font
					(size 1.27 1.27)
					(thickness 0.15)
				)
			)
		)
		(property "Author" "Antmicro"
			(at 293.5 176.1 0)
			(layer "B.Fab")
			(hide yes)
			(effects
				(font
					(size 1 1)
					(thickness 0.15)
				)
				(justify mirror)
			)
		)
		(property "Dielectric" ""
			(at 293.5 176.1 0)
			(layer "B.Fab")
			(hide yes)
			(effects
				(font
					(size 1 1)
					(thickness 0.15)
				)
				(justify mirror)
			)
		)
		(property "License" "Apache-2.0"
			(at 293.5 176.1 0)
			(layer "B.Fab")
			(hide yes)
			(effects
				(font
					(size 1 1)
					(thickness 0.15)
				)
				(justify mirror)
			)
		)
		(property "MPN" "CC0201KRX6S5BB104"
			(at 293.5 176.1 0)
			(layer "B.Fab")
			(hide yes)
			(effects
				(font
					(size 1 1)
					(thickness 0.15)
				)
				(justify mirror)
			)
		)
		(property "Manufacturer" "YAGEO"
			(at 293.5 176.1 0)
			(layer "B.Fab")
			(hide yes)
			(effects
				(font
					(size 1 1)
					(thickness 0.15)
				)
				(justify mirror)
			)
		)
		(property "Public" "False"
			(at 293.5 176.1 0)
			(layer "B.Fab")
			(hide yes)
			(effects
				(font
					(size 1 1)
					(thickness 0.15)
				)
				(justify mirror)
			)
		)
		(property "Val" "100n"
			(at 293.5 176.1 0)
			(layer "B.Fab")
			(hide yes)
			(effects
				(font
					(size 1 1)
					(thickness 0.15)
				)
				(justify mirror)
			)
		)
		(property "Voltage" ""
			(at 293.5 176.1 0)
			(layer "B.Fab")
			(hide yes)
			(effects
				(font
					(size 1 1)
					(thickness 0.15)
				)
				(justify mirror)
			)
		)
		(sheetname "DDR5")
		(sheetfile "ddr5.kicad_sch")
		(attr smd)
		(fp_rect
			(start -0.7 0.35)
			(end 0.7 -0.35)
			(stroke
				(width 0.05)
				(type default)
			)
			(fill no)
			(layer "B.CrtYd")
		)
		(fp_rect
			(start 0.3 -0.15)
			(end -0.301 0.149)
			(stroke
				(width 0.15)
				(type solid)
			)
			(fill no)
			(layer "B.Fab")
		)
		(pad "" smd roundrect
			(at -0.349 0.002 180)
			(size 0.318 0.36)
			(layers "B.Paste")
			(roundrect_rratio 0.25)
		)
		(pad "" smd roundrect
			(at 0.341 0.002 180)
			(size 0.318 0.36)
			(layers "B.Paste")
			(roundrect_rratio 0.25)
		)
		(pad "1" smd roundrect
			(at -0.321 0.002 180)
			(size 0.46 0.4)
			(layers "B.Cu" "B.Mask")
			(roundrect_rratio 0.25)
			(net 2 "VDDQ")
			(pintype "passive")
		)
		(pad "2" smd roundrect
			(at 0.32 0.002 180)
			(size 0.46 0.4)
			(layers "B.Cu" "B.Mask")
			(roundrect_rratio 0.25)
			(net 1 "GND")
			(pintype "passive")
		)
	)
)
